(kicad_pcb
	(version 20260206)
	(generator "pcbnew")
	(generator_version "10.0")
	(general
		(thickness 1.6)
		(legacy_teardrops no)
	)
	(paper "A4")
	(title_block
		(title "panther-plus-userver — 13130-1b_20150205.brd")
		(comment 1 "Honey Badger (Wiwynn) / footprints 816-824 of 1509")
	)
	(layers
		(0 "F.Cu" signal "TOP")
		(4 "In1.Cu" signal "L2")
		(6 "In2.Cu" signal "L3")
		(8 "In3.Cu" signal "L4")
		(10 "In4.Cu" signal "L5")
		(12 "In5.Cu" signal "L6")
		(14 "In6.Cu" signal "L7")
		(16 "In7.Cu" signal "L8")
		(18 "In8.Cu" signal "L9")
		(20 "In9.Cu" signal "L10")
		(22 "In10.Cu" signal "L11")
		(2 "B.Cu" signal "BOTTOM")
		(9 "F.Adhes" user "F.Adhesive")
		(11 "B.Adhes" user "B.Adhesive")
		(13 "F.Paste" user "Package Geometry/Pastemask Top")
		(15 "B.Paste" user "Package Geometry/Pastemask Bottom")
		(5 "F.SilkS" user "Ref Des/Silkscreen Top")
		(7 "B.SilkS" user "Ref Des/Silkscreen Bottom")
		(1 "F.Mask" user "Board Geometry/Soldermask Top")
		(3 "B.Mask" user "Board Geometry/Soldermask Bottom")
		(17 "Dwgs.User" user "User.Drawings")
		(19 "Cmts.User" user "User.Comments")
		(21 "Eco1.User" user "User.Eco1")
		(23 "Eco2.User" user "User.Eco2")
		(25 "Edge.Cuts" user "Board Geometry/Outline")
		(27 "Margin" user)
		(31 "F.CrtYd" user "Package Geometry/Place Bound Top")
		(29 "B.CrtYd" user "Package Geometry/Place Bound Bottom")
		(35 "F.Fab" user "Ref Des/Assembly Top")
		(33 "B.Fab" user "Ref Des/Assembly Bottom")
	)
	(footprint ""
		(layer "B.Cu")
		(at 190.4746 -11.812778 90)
		(property "Reference" "R197"
			(at 0 0 90)
			(layer "B.SilkS")
			(hide yes)
			(effects
				(font
					(size 1.27 1.27)
				)
				(justify mirror)
			)
		)
		(property "Value" "4K7R2F-GP"
			(at -0.064008 -3.993896 90)
			(unlocked yes)
			(layer "B.Fab")
			(hide yes)
			(effects
				(font
					(size 1.016 1.016)
					(thickness 0.1524)
				)
				(justify mirror)
			)
		)
		(property "Device Type" "R402H16"
			(at -0.064008 -5.517896 90)
			(unlocked yes)
			(layer "B.Fab")
			(hide yes)
			(effects
				(font
					(size 1.016 1.016)
					(thickness 0.1524)
				)
				(justify mirror)
			)
		)
		(duplicate_pad_numbers_are_jumpers no)
		(fp_rect
			(start 0.381 0.8382)
			(end -0.381 -0.8382)
			(stroke
				(width 0)
				(type default)
			)
			(fill no)
			(layer "B.CrtYd")
		)
		(fp_rect
			(start 0.381 0.8382)
			(end -0.381 -0.8382)
			(stroke
				(width 0)
				(type default)
			)
			(fill no)
			(layer "B.Fab")
		)
		(pad "1" smd custom
			(at 0 -0.4318 270)
			(size 0.127 0.127)
			(layers "B.Cu" "B.Mask" "B.Paste")
			(net "CHB_0_SA1")
			(options
				(clearance outline)
				(anchor circle)
			)
			(primitives
				(gr_poly
					(pts
						(arc
							(start -0.2032 0.2794)
							(mid -0.239121 0.264521)
							(end -0.254 0.2286)
						)
						(arc
							(start -0.254 -0.2286)
							(mid -0.239121 -0.264521)
							(end -0.2032 -0.2794)
						)
						(arc
							(start 0.2032 -0.2794)
							(mid 0.239121 -0.264521)
							(end 0.254 -0.2286)
						)
						(arc
							(start 0.254 0.2286)
							(mid 0.239121 0.264521)
							(end 0.2032 0.2794)
						)
					)
					(width 0)
					(fill yes)
				)
			)
		)
		(pad "2" smd custom
			(at 0 0.4318 270)
			(size 0.127 0.127)
			(layers "B.Cu" "B.Mask" "B.Paste")
			(net "GND")
			(options
				(clearance outline)
				(anchor circle)
			)
			(primitives
				(gr_poly
					(pts
						(arc
							(start -0.2032 0.2794)
							(mid -0.239121 0.264521)
							(end -0.254 0.2286)
						)
						(arc
							(start -0.254 -0.2286)
							(mid -0.239121 -0.264521)
							(end -0.2032 -0.2794)
						)
						(arc
							(start 0.2032 -0.2794)
							(mid 0.239121 -0.264521)
							(end 0.254 -0.2286)
						)
						(arc
							(start 0.254 0.2286)
							(mid 0.239121 0.264521)
							(end 0.2032 0.2794)
						)
					)
					(width 0)
					(fill yes)
				)
			)
		)
	)
	(footprint ""
		(layer "B.Cu")
		(at 109.982 -43.18 -90)
		(property "Reference" "C193"
			(at 0 0 90)
			(layer "B.SilkS")
			(hide yes)
			(effects
				(font
					(size 1.27 1.27)
				)
				(justify mirror)
			)
		)
		(property "Value" "SC1U10V2KX-1GP"
			(at -1.1811 -2.7051 270)
			(unlocked yes)
			(layer "B.Fab")
			(hide yes)
			(effects
				(font
					(size 1.016 1.016)
					(thickness 0.1524)
				)
				(justify mirror)
			)
		)
		(property "Device Type" "C402H22"
			(at -1.1811 -4.2291 270)
			(unlocked yes)
			(layer "B.Fab")
			(hide yes)
			(effects
				(font
					(size 1.016 1.016)
					(thickness 0.1524)
				)
				(justify mirror)
			)
		)
		(duplicate_pad_numbers_are_jumpers no)
		(fp_rect
			(start 0.381 0.7366)
			(end -0.381 -0.7366)
			(stroke
				(width 0)
				(type default)
			)
			(fill no)
			(layer "B.CrtYd")
		)
		(fp_rect
			(start 0.381 0.7366)
			(end -0.381 -0.7366)
			(stroke
				(width 0)
				(type default)
			)
			(fill no)
			(layer "B.Fab")
		)
		(pad "1" smd custom
			(at 0 -0.4572 90)
			(size 0.1143 0.1143)
			(layers "B.Cu" "B.Mask" "B.Paste")
			(net "PVCCP")
			(options
				(clearance outline)
				(anchor circle)
			)
			(primitives
				(gr_poly
					(pts
						(arc
							(start -0.254 0.1778)
							(mid -0.239121 0.213721)
							(end -0.2032 0.2286)
						)
						(arc
							(start 0.2032 0.2286)
							(mid 0.239121 0.213721)
							(end 0.254 0.1778)
						)
						(arc
							(start 0.254 -0.1778)
							(mid 0.239121 -0.213721)
							(end 0.2032 -0.2286)
						)
						(arc
							(start -0.2032 -0.2286)
							(mid -0.239121 -0.213721)
							(end -0.254 -0.1778)
						)
					)
					(width 0)
					(fill yes)
				)
			)
		)
		(pad "2" smd custom
			(at 0 0.4572 90)
			(size 0.1143 0.1143)
			(layers "B.Cu" "B.Mask" "B.Paste")
			(net "GND")
			(options
				(clearance outline)
				(anchor circle)
			)
			(primitives
				(gr_poly
					(pts
						(arc
							(start -0.254 0.1778)
							(mid -0.239121 0.213721)
							(end -0.2032 0.2286)
						)
						(arc
							(start 0.2032 0.2286)
							(mid 0.239121 0.213721)
							(end 0.254 0.1778)
						)
						(arc
							(start 0.254 -0.1778)
							(mid 0.239121 -0.213721)
							(end 0.2032 -0.2286)
						)
						(arc
							(start -0.2032 -0.2286)
							(mid -0.239121 -0.213721)
							(end -0.254 -0.1778)
						)
					)
					(width 0)
					(fill yes)
				)
			)
		)
	)
	(footprint ""
		(layer "B.Cu")
		(at 67.183 -28.321 -90)
		(property "Reference" "C45"
			(at 0 0 90)
			(layer "B.SilkS")
			(hide yes)
			(effects
				(font
					(size 1.27 1.27)
				)
				(justify mirror)
			)
		)
		(property "Value" "SCD01U16V2KX-3GP"
			(at -1.1811 -2.7051 270)
			(unlocked yes)
			(layer "B.Fab")
			(hide yes)
			(effects
				(font
					(size 1.016 1.016)
					(thickness 0.1524)
				)
				(justify mirror)
			)
		)
		(property "Device Type" "C402H22"
			(at -1.1811 -4.2291 270)
			(unlocked yes)
			(layer "B.Fab")
			(hide yes)
			(effects
				(font
					(size 1.016 1.016)
					(thickness 0.1524)
				)
				(justify mirror)
			)
		)
		(duplicate_pad_numbers_are_jumpers no)
		(fp_rect
			(start 0.381 0.7366)
			(end -0.381 -0.7366)
			(stroke
				(width 0)
				(type default)
			)
			(fill no)
			(layer "B.CrtYd")
		)
		(fp_rect
			(start 0.381 0.7366)
			(end -0.381 -0.7366)
			(stroke
				(width 0)
				(type default)
			)
			(fill no)
			(layer "B.Fab")
		)
		(pad "1" smd custom
			(at 0 -0.4572 90)
			(size 0.1143 0.1143)
			(layers "B.Cu" "B.Mask" "B.Paste")
			(net "SATA3_TX_DN0")
			(options
				(clearance outline)
				(anchor circle)
			)
			(primitives
				(gr_poly
					(pts
						(arc
							(start -0.254 0.1778)
							(mid -0.239121 0.213721)
							(end -0.2032 0.2286)
						)
						(arc
							(start 0.2032 0.2286)
							(mid 0.239121 0.213721)
							(end 0.254 0.1778)
						)
						(arc
							(start 0.254 -0.1778)
							(mid 0.239121 -0.213721)
							(end 0.2032 -0.2286)
						)
						(arc
							(start -0.2032 -0.2286)
							(mid -0.239121 -0.213721)
							(end -0.254 -0.1778)
						)
					)
					(width 0)
					(fill yes)
				)
			)
		)
		(pad "2" smd custom
			(at 0 0.4572 90)
			(size 0.1143 0.1143)
			(layers "B.Cu" "B.Mask" "B.Paste")
			(net "SATA3_TX_C_DN0")
			(options
				(clearance outline)
				(anchor circle)
			)
			(primitives
				(gr_poly
					(pts
						(arc
							(start -0.254 0.1778)
							(mid -0.239121 0.213721)
							(end -0.2032 0.2286)
						)
						(arc
							(start 0.2032 0.2286)
							(mid 0.239121 0.213721)
							(end 0.254 0.1778)
						)
						(arc
							(start 0.254 -0.1778)
							(mid 0.239121 -0.213721)
							(end 0.2032 -0.2286)
						)
						(arc
							(start -0.2032 -0.2286)
							(mid -0.239121 -0.213721)
							(end -0.254 -0.1778)
						)
					)
					(width 0)
					(fill yes)
				)
			)
		)
	)
	(footprint ""
		(layer "B.Cu")
		(at 161.163 -59.309)
		(property "Reference" "C361"
			(at 0 0 0)
			(layer "B.SilkS")
			(hide yes)
			(effects
				(font
					(size 1.27 1.27)
				)
				(justify mirror)
			)
		)
		(property "Value" "SC47U6D3V5MX-1-GP"
			(at 0 -4.9022 0)
			(unlocked yes)
			(layer "B.Fab")
			(hide yes)
			(effects
				(font
					(size 1.016 1.016)
					(thickness 0.1524)
				)
				(justify mirror)
			)
		)
		(property "Device Type" "C805H54"
			(at 0 -6.8072 0)
			(unlocked yes)
			(layer "B.Fab")
			(hide yes)
			(effects
				(font
					(size 1.016 1.016)
					(thickness 0.1524)
				)
				(justify mirror)
			)
		)
		(duplicate_pad_numbers_are_jumpers no)
		(fp_line
			(start -0.6096 0)
			(end 0.6096 0)
			(stroke
				(width 0.3048)
				(type default)
			)
			(layer "B.SilkS")
		)
		(fp_poly
			(pts
				(xy 0.9017 1.4351) (xy -0.9017 1.4351) (xy -0.9017 -1.4351) (xy 0.9017 -1.4351)
			)
			(stroke
				(width 0)
				(type default)
			)
			(fill no)
			(layer "B.CrtYd")
		)
		(fp_poly
			(pts
				(xy -0.9017 1.4351) (xy -0.9017 -1.4351) (xy 0.9017 -1.4351) (xy 0.9017 1.4351)
			)
			(stroke
				(width 0)
				(type default)
			)
			(fill no)
			(layer "B.Fab")
		)
		(pad "1" smd rect
			(at 0 -0.8382 180)
			(size 1.5494 0.9398)
			(layers "B.Cu" "B.Mask" "B.Paste")
			(net "PV_VDDR")
		)
		(pad "2" smd rect
			(at 0 0.8382 180)
			(size 1.5494 0.9398)
			(layers "B.Cu" "B.Mask" "B.Paste")
			(net "GND")
		)
	)
	(footprint ""
		(layer "B.Cu")
		(at 163.9062 -13.235178 180)
		(property "Reference" "C293"
			(at 0 0 0)
			(layer "B.SilkS")
			(hide yes)
			(effects
				(font
					(size 1.27 1.27)
				)
				(justify mirror)
			)
		)
		(property "Value" "SC10U6D3V3MX-GP"
			(at 0.0254 -2.0193 180)
			(unlocked yes)
			(layer "B.Fab")
			(hide yes)
			(effects
				(font
					(size 1.016 1.016)
					(thickness 0.1524)
				)
				(justify mirror)
			)
		)
		(property "Device Type" "C603H38"
			(at 0.0254 -3.5433 180)
			(unlocked yes)
			(layer "B.Fab")
			(hide yes)
			(effects
				(font
					(size 1.016 1.016)
					(thickness 0.1524)
				)
				(justify mirror)
			)
		)
		(duplicate_pad_numbers_are_jumpers no)
		(fp_line
			(start 0.4064 0)
			(end -0.4064 0)
			(stroke
				(width 0.2286)
				(type default)
			)
			(layer "B.SilkS")
		)
		(fp_rect
			(start 0.635 1.1811)
			(end -0.635 -1.1811)
			(stroke
				(width 0)
				(type default)
			)
			(fill no)
			(layer "B.CrtYd")
		)
		(fp_rect
			(start 0.635 1.1811)
			(end -0.635 -1.1811)
			(stroke
				(width 0)
				(type default)
			)
			(fill no)
			(layer "B.Fab")
		)
		(pad "1" smd custom
			(at 0 -0.6604)
			(size 0.19685 0.19685)
			(layers "B.Cu" "B.Mask" "B.Paste")
			(net "PV_VDDR")
			(options
				(clearance outline)
				(anchor circle)
			)
			(primitives
				(gr_poly
					(pts
						(arc
							(start 0.508 0.2921)
							(mid 0.478242 0.363942)
							(end 0.4064 0.3937)
						)
						(arc
							(start -0.4064 0.3937)
							(mid -0.478242 0.363942)
							(end -0.508 0.2921)
						)
						(arc
							(start -0.508 -0.2921)
							(mid -0.478242 -0.363942)
							(end -0.4064 -0.3937)
						)
						(arc
							(start 0.4064 -0.3937)
							(mid 0.478242 -0.363942)
							(end 0.508 -0.2921)
						)
					)
					(width 0)
					(fill yes)
				)
			)
		)
		(pad "2" smd custom
			(at 0 0.6604)
			(size 0.19685 0.19685)
			(layers "B.Cu" "B.Mask" "B.Paste")
			(net "GND")
			(options
				(clearance outline)
				(anchor circle)
			)
			(primitives
				(gr_poly
					(pts
						(arc
							(start 0.508 0.2921)
							(mid 0.478242 0.363942)
							(end 0.4064 0.3937)
						)
						(arc
							(start -0.4064 0.3937)
							(mid -0.478242 0.363942)
							(end -0.508 0.2921)
						)
						(arc
							(start -0.508 -0.2921)
							(mid -0.478242 -0.363942)
							(end -0.4064 -0.3937)
						)
						(arc
							(start 0.4064 -0.3937)
							(mid 0.478242 -0.363942)
							(end 0.508 -0.2921)
						)
					)
					(width 0)
					(fill yes)
				)
			)
		)
	)
	(footprint ""
		(layer "B.Cu")
		(at 197.485 -32.004 -90)
		(property "Reference" "R150"
			(at 0 0 90)
			(layer "B.SilkS")
			(hide yes)
			(effects
				(font
					(size 1.27 1.27)
				)
				(justify mirror)
			)
		)
		(property "Value" "300R2F-GP"
			(at -1.7907 -1.1176 270)
			(unlocked yes)
			(layer "B.Fab")
			(hide yes)
			(effects
				(font
					(size 1.016 1.016)
					(thickness 0.1524)
				)
				(justify mirror)
			)
		)
		(property "Device Type" "R402H16"
			(at -1.7907 -2.6416 270)
			(unlocked yes)
			(layer "B.Fab")
			(hide yes)
			(effects
				(font
					(size 1.016 1.016)
					(thickness 0.1524)
				)
				(justify mirror)
			)
		)
		(duplicate_pad_numbers_are_jumpers no)
		(fp_rect
			(start 0.381 0.8382)
			(end -0.381 -0.8382)
			(stroke
				(width 0)
				(type default)
			)
			(fill no)
			(layer "B.CrtYd")
		)
		(fp_rect
			(start 0.381 0.8382)
			(end -0.381 -0.8382)
			(stroke
				(width 0)
				(type default)
			)
			(fill no)
			(layer "B.Fab")
		)
		(pad "1" smd custom
			(at 0 -0.4318 90)
			(size 0.127 0.127)
			(layers "B.Cu" "B.Mask" "B.Paste")
			(net "PORT80_R_BIT1")
			(options
				(clearance outline)
				(anchor circle)
			)
			(primitives
				(gr_poly
					(pts
						(arc
							(start -0.2032 0.2794)
							(mid -0.239121 0.264521)
							(end -0.254 0.2286)
						)
						(arc
							(start -0.254 -0.2286)
							(mid -0.239121 -0.264521)
							(end -0.2032 -0.2794)
						)
						(arc
							(start 0.2032 -0.2794)
							(mid 0.239121 -0.264521)
							(end 0.254 -0.2286)
						)
						(arc
							(start 0.254 0.2286)
							(mid 0.239121 0.264521)
							(end 0.2032 0.2794)
						)
					)
					(width 0)
					(fill yes)
				)
			)
		)
		(pad "2" smd custom
			(at 0 0.4318 90)
			(size 0.127 0.127)
			(layers "B.Cu" "B.Mask" "B.Paste")
			(net "P3V3_STBY")
			(options
				(clearance outline)
				(anchor circle)
			)
			(primitives
				(gr_poly
					(pts
						(arc
							(start -0.2032 0.2794)
							(mid -0.239121 0.264521)
							(end -0.254 0.2286)
						)
						(arc
							(start -0.254 -0.2286)
							(mid -0.239121 -0.264521)
							(end -0.2032 -0.2794)
						)
						(arc
							(start 0.2032 -0.2794)
							(mid 0.239121 -0.264521)
							(end 0.254 -0.2286)
						)
						(arc
							(start 0.254 0.2286)
							(mid 0.239121 0.264521)
							(end 0.2032 0.2794)
						)
					)
					(width 0)
					(fill yes)
				)
			)
		)
	)
	(footprint ""
		(layer "B.Cu")
		(at 157.6832 -59.6646)
		(property "Reference" "C330"
			(at 0 0 0)
			(layer "B.SilkS")
			(hide yes)
			(effects
				(font
					(size 1.27 1.27)
				)
				(justify mirror)
			)
		)
		(property "Value" "SCD1U16V2KX-3GP"
			(at -1.8923 -1.2065 0)
			(unlocked yes)
			(layer "B.Fab")
			(hide yes)
			(effects
				(font
					(size 1.016 1.016)
					(thickness 0.1524)
				)
				(justify mirror)
			)
		)
		(property "Device Type" "C402H22"
			(at -1.8923 -2.7305 0)
			(unlocked yes)
			(layer "B.Fab")
			(hide yes)
			(effects
				(font
					(size 1.016 1.016)
					(thickness 0.1524)
				)
				(justify mirror)
			)
		)
		(duplicate_pad_numbers_are_jumpers no)
		(fp_rect
			(start 0.381 0.7366)
			(end -0.381 -0.7366)
			(stroke
				(width 0)
				(type default)
			)
			(fill no)
			(layer "B.CrtYd")
		)
		(fp_rect
			(start 0.381 0.7366)
			(end -0.381 -0.7366)
			(stroke
				(width 0)
				(type default)
			)
			(fill no)
			(layer "B.Fab")
		)
		(pad "1" smd custom
			(at 0 -0.4572 180)
			(size 0.1143 0.1143)
			(layers "B.Cu" "B.Mask" "B.Paste")
			(net "PV_VDDR")
			(options
				(clearance outline)
				(anchor circle)
			)
			(primitives
				(gr_poly
					(pts
						(arc
							(start -0.254 0.1778)
							(mid -0.239121 0.213721)
							(end -0.2032 0.2286)
						)
						(arc
							(start 0.2032 0.2286)
							(mid 0.239121 0.213721)
							(end 0.254 0.1778)
						)
						(arc
							(start 0.254 -0.1778)
							(mid 0.239121 -0.213721)
							(end 0.2032 -0.2286)
						)
						(arc
							(start -0.2032 -0.2286)
							(mid -0.239121 -0.213721)
							(end -0.254 -0.1778)
						)
					)
					(width 0)
					(fill yes)
				)
			)
		)
		(pad "2" smd custom
			(at 0 0.4572 180)
			(size 0.1143 0.1143)
			(layers "B.Cu" "B.Mask" "B.Paste")
			(net "GND")
			(options
				(clearance outline)
				(anchor circle)
			)
			(primitives
				(gr_poly
					(pts
						(arc
							(start -0.254 0.1778)
							(mid -0.239121 0.213721)
							(end -0.2032 0.2286)
						)
						(arc
							(start 0.2032 0.2286)
							(mid 0.239121 0.213721)
							(end 0.254 0.1778)
						)
						(arc
							(start 0.254 -0.1778)
							(mid 0.239121 -0.213721)
							(end 0.2032 -0.2286)
						)
						(arc
							(start -0.2032 -0.2286)
							(mid -0.239121 -0.213721)
							(end -0.254 -0.1778)
						)
					)
					(width 0)
					(fill yes)
				)
			)
		)
	)
	(footprint ""
		(layer "B.Cu")
		(at 80.518 -35.4584 -90)
		(property "Reference" "TP36"
			(at 0 0 90)
			(layer "B.SilkS")
			(hide yes)
			(effects
				(font
					(size 1.27 1.27)
				)
				(justify mirror)
			)
		)
		(property "Value" "TPAD24"
			(at 0 -2.9972 270)
			(unlocked yes)
			(layer "B.Fab")
			(hide yes)
			(effects
				(font
					(size 1.016 1.016)
					(thickness 0.1524)
				)
				(justify mirror)
			)
		)
		(property "Device Type" "TPAD24"
			(at 0 -4.5212 270)
			(unlocked yes)
			(layer "B.Fab")
			(hide yes)
			(effects
				(font
					(size 1.016 1.016)
					(thickness 0.1524)
				)
				(justify mirror)
			)
		)
		(duplicate_pad_numbers_are_jumpers no)
		(fp_poly
			(pts
				(arc
					(start 0 -0.3048)
					(mid 0 0.3048)
					(end 0 -0.3048)
				)
			)
			(stroke
				(width 0)
				(type default)
			)
			(fill no)
			(layer "B.CrtYd")
		)
		(fp_poly
			(pts
				(arc
					(start 0 -0.6096)
					(mid 0 0.6096)
					(end 0 -0.6096)
				)
			)
			(stroke
				(width 0)
				(type default)
			)
			(fill no)
			(layer "B.Fab")
		)
		(pad "1" smd circle
			(at 0 0 90)
			(size 0.6096 0.6096)
			(layers "B.Cu" "B.Mask" "B.Paste")
			(net "TP_CPU_RSVD13")
		)
	)
	(footprint ""
		(layer "B.Cu")
		(at 67.0306 -37.1602 90)
		(property "Reference" "PR128"
			(at 0 0 90)
			(layer "B.SilkS")
			(hide yes)
			(effects
				(font
					(size 1.27 1.27)
				)
				(justify mirror)
			)
		)
		(property "Value" "0R2J-2-GP"
			(at -0.064008 -3.993896 90)
			(unlocked yes)
			(layer "B.Fab")
			(hide yes)
			(effects
				(font
					(size 1.016 1.016)
					(thickness 0.1524)
				)
				(justify mirror)
			)
		)
		(property "Device Type" "R402H16"
			(at -0.064008 -5.517896 90)
			(unlocked yes)
			(layer "B.Fab")
			(hide yes)
			(effects
				(font
					(size 1.016 1.016)
					(thickness 0.1524)
				)
				(justify mirror)
			)
		)
		(duplicate_pad_numbers_are_jumpers no)
		(fp_rect
			(start 0.381 0.8382)
			(end -0.381 -0.8382)
			(stroke
				(width 0)
				(type default)
			)
			(fill no)
			(layer "B.CrtYd")
		)
		(fp_rect
			(start 0.381 0.8382)
			(end -0.381 -0.8382)
			(stroke
				(width 0)
				(type default)
			)
			(fill no)
			(layer "B.Fab")
		)
		(pad "1" smd custom
			(at 0 -0.4318 270)
			(size 0.127 0.127)
			(layers "B.Cu" "B.Mask" "B.Paste")
			(net "PMU_SLP_DDRVTT#")
			(options
				(clearance outline)
				(anchor circle)
			)
			(primitives
				(gr_poly
					(pts
						(arc
							(start -0.2032 0.2794)
							(mid -0.239121 0.264521)
							(end -0.254 0.2286)
						)
						(arc
							(start -0.254 -0.2286)
							(mid -0.239121 -0.264521)
							(end -0.2032 -0.2794)
						)
						(arc
							(start 0.2032 -0.2794)
							(mid 0.239121 -0.264521)
							(end 0.254 -0.2286)
						)
						(arc
							(start 0.254 0.2286)
							(mid 0.239121 0.264521)
							(end 0.2032 0.2794)
						)
					)
					(width 0)
					(fill yes)
				)
			)
		)
		(pad "2" smd custom
			(at 0 0.4318 270)
			(size 0.127 0.127)
			(layers "B.Cu" "B.Mask" "B.Paste")
			(net "PMU_SLP_INA_DDRVTT#")
			(options
				(clearance outline)
				(anchor circle)
			)
			(primitives
				(gr_poly
					(pts
						(arc
							(start -0.2032 0.2794)
							(mid -0.239121 0.264521)
							(end -0.254 0.2286)
						)
						(arc
							(start -0.254 -0.2286)
							(mid -0.239121 -0.264521)
							(end -0.2032 -0.2794)
						)
						(arc
							(start 0.2032 -0.2794)
							(mid 0.239121 -0.264521)
							(end 0.254 -0.2286)
						)
						(arc
							(start 0.254 0.2286)
							(mid 0.239121 0.264521)
							(end 0.2032 0.2794)
						)
					)
					(width 0)
					(fill yes)
				)
			)
		)
	)
)
